# T6G (Grand Teton) — schematic netlist excerpt (pin names and nets, part order shuffled) for the footprints in the layout excerpt that follows; sources: Cadence DE-HDL packaged netlist, KiCad conversion of 04192023_DAF0TMB3IC0_F0TG_MB_C_brd_V02_OCP.brd

R163  Q_RES  33 5% CHIP  pkg 0402LF  page 80 : A = FM_I3C_CPU0_MUX0_OE_R_N ; B = FM_I3C_CPU0_MUX0_OE_N
PC169  Q_CAP  560PF 50V 10% EMPTY  pkg C0402  page 208 : A = SW_PVDD11_S3_P0_SW1 ; B = SW_PVDD11_S3_P0_SW1_RC

(kicad_pcb
	(version 20260206)
	(generator "pcbnew")
	(generator_version "10.0")
	(general
		(thickness 1.6)
		(legacy_teardrops no)
	)
	(paper "A4")
	(title_block
		(title "04192023_DAF0TMB3IC0_F0TG_MB_C_brd_V02_OCP.brd")
		(comment 1 "Grand Teton / footprints 1730-1731 of 8354")
	)
	(layers
		(0 "F.Cu" signal "TOP")
		(4 "In1.Cu" signal "GND")
		(6 "In2.Cu" signal "IN1")
		(8 "In3.Cu" signal "GND1")
		(10 "In4.Cu" signal "IN2")
		(12 "In5.Cu" signal "GND2")
		(14 "In6.Cu" signal "IN3")
		(16 "In7.Cu" signal "GND3")
		(18 "In8.Cu" signal "VCC")
		(20 "In9.Cu" signal "VCC1")
		(22 "In10.Cu" signal "GND4")
		(24 "In11.Cu" signal "IN4")
		(26 "In12.Cu" signal "GND5")
		(28 "In13.Cu" signal "IN5")
		(30 "In14.Cu" signal "GND6")
		(32 "In15.Cu" signal "IN6")
		(34 "In16.Cu" signal "GND7")
		(2 "B.Cu" signal "BOTTOM")
		(9 "F.Adhes" user "F.Adhesive")
		(11 "B.Adhes" user "B.Adhesive")
		(13 "F.Paste" user "Package Geometry/Pastemask Top")
		(15 "B.Paste" user "Package Geometry/Pastemask Bottom")
		(5 "F.SilkS" user "Ref Des/Silkscreen Top")
		(7 "B.SilkS" user "Ref Des/Silkscreen Bottom")
		(1 "F.Mask" user "Board Geometry/Soldermask Top")
		(3 "B.Mask" user "Board Geometry/Soldermask Bottom")
		(17 "Dwgs.User" user "User.Drawings")
		(19 "Cmts.User" user "User.Comments")
		(21 "Eco1.User" user "User.Eco1")
		(23 "Eco2.User" user "User.Eco2")
		(25 "Edge.Cuts" user "Board Geometry/Outline")
		(27 "Margin" user)
		(31 "F.CrtYd" user "Package Geometry/Place Bound Top")
		(29 "B.CrtYd" user "Package Geometry/Place Bound Bottom")
		(35 "F.Fab" user "Ref Des/Assembly Top")
		(33 "B.Fab" user "Ref Des/Assembly Bottom")
	)
	(footprint ""
		(layer "F.Cu")
		(at 175.641 -100.294948 -90)
		(property "Reference" "R163"
			(at 0 0 270)
			(layer "F.SilkS")
			(hide yes)
			(effects
				(font
					(size 1.27 1.27)
				)
			)
		)
		(property "Value" ""
			(at 0 0 270)
			(layer "F.Fab")
			(effects
				(font
					(size 1.27 1.27)
				)
			)
		)
		(duplicate_pad_numbers_are_jumpers no)
		(fp_line
			(start -0.7874 0.4064)
			(end -0.7874 -0.4064)
			(stroke
				(width 0.1524)
				(type default)
			)
			(layer "F.SilkS")
		)
		(fp_line
			(start 0.7874 0.4064)
			(end -0.7874 0.4064)
			(stroke
				(width 0.1524)
				(type default)
			)
			(layer "F.SilkS")
		)
		(fp_line
			(start -0.7874 -0.4064)
			(end 0.7874 -0.4064)
			(stroke
				(width 0.1524)
				(type default)
			)
			(layer "F.SilkS")
		)
		(fp_line
			(start 0.7874 -0.4064)
			(end 0.7874 0.4064)
			(stroke
				(width 0.1524)
				(type default)
			)
			(layer "F.SilkS")
		)
		(fp_line
			(start -0.67945 0.3048)
			(end -0.67945 -0.305054)
			(stroke
				(width 0.1)
				(type default)
			)
			(layer "F.Fab")
		)
		(fp_line
			(start -0.12065 0.3048)
			(end -0.67945 0.3048)
			(stroke
				(width 0.1)
				(type default)
			)
			(layer "F.Fab")
		)
		(fp_line
			(start 0.120396 0.3048)
			(end 0.120396 0.2794)
			(stroke
				(width 0.1)
				(type default)
			)
			(layer "F.Fab")
		)
		(fp_line
			(start 0.67945 0.3048)
			(end 0.120396 0.3048)
			(stroke
				(width 0.1)
				(type default)
			)
			(layer "F.Fab")
		)
		(fp_line
			(start -0.12065 0.2794)
			(end -0.12065 0.3048)
			(stroke
				(width 0.1)
				(type default)
			)
			(layer "F.Fab")
		)
		(fp_line
			(start 0.120396 0.2794)
			(end -0.12065 0.2794)
			(stroke
				(width 0.1)
				(type default)
			)
			(layer "F.Fab")
		)
		(fp_line
			(start -0.12065 -0.2794)
			(end 0.12065 -0.2794)
			(stroke
				(width 0.1)
				(type default)
			)
			(layer "F.Fab")
		)
		(fp_line
			(start 0.12065 -0.2794)
			(end 0.12065 -0.3048)
			(stroke
				(width 0.1)
				(type default)
			)
			(layer "F.Fab")
		)
		(fp_line
			(start 0.12065 -0.3048)
			(end 0.67945 -0.3048)
			(stroke
				(width 0.1)
				(type default)
			)
			(layer "F.Fab")
		)
		(fp_line
			(start 0.67945 -0.3048)
			(end 0.67945 0.3048)
			(stroke
				(width 0.1)
				(type default)
			)
			(layer "F.Fab")
		)
		(fp_line
			(start -0.67945 -0.305054)
			(end -0.12065 -0.305054)
			(stroke
				(width 0.1)
				(type default)
			)
			(layer "F.Fab")
		)
		(fp_line
			(start -0.12065 -0.305054)
			(end -0.12065 -0.2794)
			(stroke
				(width 0.1)
				(type default)
			)
			(layer "F.Fab")
		)
		(pad "1" smd circle
			(at -0.40005 0 270)
			(size 0 0)
			(layers "F.Cu" "F.Mask" "F.Paste")
			(net "FM_I3C_CPU0_MUX0_OE_R_N")
		)
		(pad "2" smd circle
			(at 0.40005 0 270)
			(size 0 0)
			(layers "F.Cu" "F.Mask" "F.Paste")
			(net "FM_I3C_CPU0_MUX0_OE_N")
		)
	)
	(footprint ""
		(layer "F.Cu")
		(at 419.950138 -348.110556 180)
		(property "Reference" "PC169"
			(at 0 0 180)
			(layer "F.SilkS")
			(hide yes)
			(effects
				(font
					(size 1.27 1.27)
				)
			)
		)
		(property "Value" ""
			(at 0 0 180)
			(layer "F.Fab")
			(effects
				(font
					(size 1.27 1.27)
				)
			)
		)
		(duplicate_pad_numbers_are_jumpers no)
		(fp_line
			(start 0.7874 0.4064)
			(end -0.7874 0.4064)
			(stroke
				(width 0.1524)
				(type default)
			)
			(layer "F.SilkS")
		)
		(fp_line
			(start 0.7874 -0.4064)
			(end 0.7874 0.4064)
			(stroke
				(width 0.1524)
				(type default)
			)
			(layer "F.SilkS")
		)
		(fp_line
			(start -0.7874 0.4064)
			(end -0.7874 -0.4064)
			(stroke
				(width 0.1524)
				(type default)
			)
			(layer "F.SilkS")
		)
		(fp_line
			(start -0.7874 -0.4064)
			(end 0.7874 -0.4064)
			(stroke
				(width 0.1524)
				(type default)
			)
			(layer "F.SilkS")
		)
		(fp_line
			(start 0.67945 0.3048)
			(end 0.120396 0.3048)
			(stroke
				(width 0.1)
				(type default)
			)
			(layer "F.Fab")
		)
		(fp_line
			(start 0.67945 -0.3048)
			(end 0.67945 0.3048)
			(stroke
				(width 0.1)
				(type default)
			)
			(layer "F.Fab")
		)
		(fp_line
			(start 0.12065 -0.2794)
			(end 0.12065 -0.3048)
			(stroke
				(width 0.1)
				(type default)
			)
			(layer "F.Fab")
		)
		(fp_line
			(start 0.12065 -0.3048)
			(end 0.67945 -0.3048)
			(stroke
				(width 0.1)
				(type default)
			)
			(layer "F.Fab")
		)
		(fp_line
			(start 0.120396 0.3048)
			(end 0.120396 0.2794)
			(stroke
				(width 0.1)
				(type default)
			)
			(layer "F.Fab")
		)
		(fp_line
			(start 0.120396 0.2794)
			(end -0.12065 0.2794)
			(stroke
				(width 0.1)
				(type default)
			)
			(layer "F.Fab")
		)
		(fp_line
			(start -0.12065 0.3048)
			(end -0.67945 0.3048)
			(stroke
				(width 0.1)
				(type default)
			)
			(layer "F.Fab")
		)
		(fp_line
			(start -0.12065 0.2794)
			(end -0.12065 0.3048)
			(stroke
				(width 0.1)
				(type default)
			)
			(layer "F.Fab")
		)
		(fp_line
			(start -0.12065 -0.2794)
			(end 0.12065 -0.2794)
			(stroke
				(width 0.1)
				(type default)
			)
			(layer "F.Fab")
		)
		(fp_line
			(start -0.12065 -0.305054)
			(end -0.12065 -0.2794)
			(stroke
				(width 0.1)
				(type default)
			)
			(layer "F.Fab")
		)
		(fp_line
			(start -0.67945 0.3048)
			(end -0.67945 -0.305054)
			(stroke
				(width 0.1)
				(type default)
			)
			(layer "F.Fab")
		)
		(fp_line
			(start -0.67945 -0.305054)
			(end -0.12065 -0.305054)
			(stroke
				(width 0.1)
				(type default)
			)
			(layer "F.Fab")
		)
		(pad "1" smd circle
			(at -0.40005 0 180)
			(size 0 0)
			(layers "F.Cu" "F.Mask" "F.Paste")
			(net "SW_PVDD11_S3_P0_SW1")
		)
		(pad "2" smd circle
			(at 0.40005 0 180)
			(size 0 0)
			(layers "F.Cu" "F.Mask" "F.Paste")
			(net "SW_PVDD11_S3_P0_SW1_RC")
		)
	)
)
